# T6G (Grand Teton) — schematic netlist excerpt (pin names and nets, part order shuffled) for the footprints in the layout excerpt that follows; sources: Cadence DE-HDL packaged netlist, KiCad conversion of 04192023_DAF0TMB3IC0_F0TG_MB_C_brd_V02_OCP.brd

R8317  Q_RES  1K 1% CHIP  pkg 0402LF  page 193 : A = PVDD18_S5_P0 ; B = PVDDCR_CPU0_P0_RESET_N_R
PC92  Q_CAP  0.22UF 16V 10% X7R  pkg 0402  page 201 : A = SW_PVDDCR_CPU1_P0_BOOT1_R ; B = SW_PVDDCR_CPU1_P0_BOOTR1

(kicad_pcb
	(version 20260206)
	(generator "pcbnew")
	(generator_version "10.0")
	(general
		(thickness 1.6)
		(legacy_teardrops no)
	)
	(paper "A4")
	(title_block
		(title "04192023_DAF0TMB3IC0_F0TG_MB_C_brd_V02_OCP.brd")
		(comment 1 "Grand Teton / footprints 2171-2172 of 8354")
	)
	(layers
		(0 "F.Cu" signal "TOP")
		(4 "In1.Cu" signal "GND")
		(6 "In2.Cu" signal "IN1")
		(8 "In3.Cu" signal "GND1")
		(10 "In4.Cu" signal "IN2")
		(12 "In5.Cu" signal "GND2")
		(14 "In6.Cu" signal "IN3")
		(16 "In7.Cu" signal "GND3")
		(18 "In8.Cu" signal "VCC")
		(20 "In9.Cu" signal "VCC1")
		(22 "In10.Cu" signal "GND4")
		(24 "In11.Cu" signal "IN4")
		(26 "In12.Cu" signal "GND5")
		(28 "In13.Cu" signal "IN5")
		(30 "In14.Cu" signal "GND6")
		(32 "In15.Cu" signal "IN6")
		(34 "In16.Cu" signal "GND7")
		(2 "B.Cu" signal "BOTTOM")
		(9 "F.Adhes" user "F.Adhesive")
		(11 "B.Adhes" user "B.Adhesive")
		(13 "F.Paste" user "Package Geometry/Pastemask Top")
		(15 "B.Paste" user "Package Geometry/Pastemask Bottom")
		(5 "F.SilkS" user "Ref Des/Silkscreen Top")
		(7 "B.SilkS" user "Ref Des/Silkscreen Bottom")
		(1 "F.Mask" user "Board Geometry/Soldermask Top")
		(3 "B.Mask" user "Board Geometry/Soldermask Bottom")
		(17 "Dwgs.User" user "User.Drawings")
		(19 "Cmts.User" user "User.Comments")
		(21 "Eco1.User" user "User.Eco1")
		(23 "Eco2.User" user "User.Eco2")
		(25 "Edge.Cuts" user "Board Geometry/Outline")
		(27 "Margin" user)
		(31 "F.CrtYd" user "Package Geometry/Place Bound Top")
		(29 "B.CrtYd" user "Package Geometry/Place Bound Bottom")
		(35 "F.Fab" user "Ref Des/Assembly Top")
		(33 "B.Fab" user "Ref Des/Assembly Bottom")
	)
	(footprint ""
		(layer "F.Cu")
		(at 372.937278 -141.472158)
		(property "Reference" "R8317"
			(at 0 0 0)
			(layer "F.SilkS")
			(hide yes)
			(effects
				(font
					(size 1.27 1.27)
				)
			)
		)
		(property "Value" ""
			(at 0 0 0)
			(layer "F.Fab")
			(effects
				(font
					(size 1.27 1.27)
				)
			)
		)
		(duplicate_pad_numbers_are_jumpers no)
		(fp_line
			(start -0.7874 -0.4064)
			(end 0.7874 -0.4064)
			(stroke
				(width 0.1524)
				(type default)
			)
			(layer "F.SilkS")
		)
		(fp_line
			(start -0.7874 0.4064)
			(end -0.7874 -0.4064)
			(stroke
				(width 0.1524)
				(type default)
			)
			(layer "F.SilkS")
		)
		(fp_line
			(start 0.7874 -0.4064)
			(end 0.7874 0.4064)
			(stroke
				(width 0.1524)
				(type default)
			)
			(layer "F.SilkS")
		)
		(fp_line
			(start 0.7874 0.4064)
			(end -0.7874 0.4064)
			(stroke
				(width 0.1524)
				(type default)
			)
			(layer "F.SilkS")
		)
		(fp_line
			(start -0.67945 -0.305054)
			(end -0.12065 -0.305054)
			(stroke
				(width 0.1)
				(type default)
			)
			(layer "F.Fab")
		)
		(fp_line
			(start -0.67945 0.3048)
			(end -0.67945 -0.305054)
			(stroke
				(width 0.1)
				(type default)
			)
			(layer "F.Fab")
		)
		(fp_line
			(start -0.12065 -0.305054)
			(end -0.12065 -0.2794)
			(stroke
				(width 0.1)
				(type default)
			)
			(layer "F.Fab")
		)
		(fp_line
			(start -0.12065 -0.2794)
			(end 0.12065 -0.2794)
			(stroke
				(width 0.1)
				(type default)
			)
			(layer "F.Fab")
		)
		(fp_line
			(start -0.12065 0.2794)
			(end -0.12065 0.3048)
			(stroke
				(width 0.1)
				(type default)
			)
			(layer "F.Fab")
		)
		(fp_line
			(start -0.12065 0.3048)
			(end -0.67945 0.3048)
			(stroke
				(width 0.1)
				(type default)
			)
			(layer "F.Fab")
		)
		(fp_line
			(start 0.120396 0.2794)
			(end -0.12065 0.2794)
			(stroke
				(width 0.1)
				(type default)
			)
			(layer "F.Fab")
		)
		(fp_line
			(start 0.120396 0.3048)
			(end 0.120396 0.2794)
			(stroke
				(width 0.1)
				(type default)
			)
			(layer "F.Fab")
		)
		(fp_line
			(start 0.12065 -0.3048)
			(end 0.67945 -0.3048)
			(stroke
				(width 0.1)
				(type default)
			)
			(layer "F.Fab")
		)
		(fp_line
			(start 0.12065 -0.2794)
			(end 0.12065 -0.3048)
			(stroke
				(width 0.1)
				(type default)
			)
			(layer "F.Fab")
		)
		(fp_line
			(start 0.67945 -0.3048)
			(end 0.67945 0.3048)
			(stroke
				(width 0.1)
				(type default)
			)
			(layer "F.Fab")
		)
		(fp_line
			(start 0.67945 0.3048)
			(end 0.120396 0.3048)
			(stroke
				(width 0.1)
				(type default)
			)
			(layer "F.Fab")
		)
		(pad "1" smd circle
			(at -0.40005 0)
			(size 0 0)
			(layers "F.Cu" "F.Mask" "F.Paste")
			(net "PVDD18_S5_P0")
		)
		(pad "2" smd circle
			(at 0.40005 0)
			(size 0 0)
			(layers "F.Cu" "F.Mask" "F.Paste")
			(net "PVDDCR_CPU0_P0_RESET_N_R")
		)
	)
	(footprint ""
		(layer "F.Cu")
		(at 336.844894 -339.625432 -90)
		(property "Reference" "PC92"
			(at 0 0 270)
			(layer "F.SilkS")
			(hide yes)
			(effects
				(font
					(size 1.27 1.27)
				)
			)
		)
		(property "Value" ""
			(at 0 0 270)
			(layer "F.Fab")
			(effects
				(font
					(size 1.27 1.27)
				)
			)
		)
		(duplicate_pad_numbers_are_jumpers no)
		(fp_line
			(start -0.7874 0.4064)
			(end -0.7874 -0.4064)
			(stroke
				(width 0.1524)
				(type default)
			)
			(layer "F.SilkS")
		)
		(fp_line
			(start 0.7874 0.4064)
			(end -0.7874 0.4064)
			(stroke
				(width 0.1524)
				(type default)
			)
			(layer "F.SilkS")
		)
		(fp_line
			(start -0.7874 -0.4064)
			(end 0.7874 -0.4064)
			(stroke
				(width 0.1524)
				(type default)
			)
			(layer "F.SilkS")
		)
		(fp_line
			(start 0.7874 -0.4064)
			(end 0.7874 0.4064)
			(stroke
				(width 0.1524)
				(type default)
			)
			(layer "F.SilkS")
		)
		(fp_line
			(start -0.67945 0.3048)
			(end -0.67945 -0.305054)
			(stroke
				(width 0.1)
				(type default)
			)
			(layer "F.Fab")
		)
		(fp_line
			(start -0.12065 0.3048)
			(end -0.67945 0.3048)
			(stroke
				(width 0.1)
				(type default)
			)
			(layer "F.Fab")
		)
		(fp_line
			(start 0.120396 0.3048)
			(end 0.120396 0.2794)
			(stroke
				(width 0.1)
				(type default)
			)
			(layer "F.Fab")
		)
		(fp_line
			(start 0.67945 0.3048)
			(end 0.120396 0.3048)
			(stroke
				(width 0.1)
				(type default)
			)
			(layer "F.Fab")
		)
		(fp_line
			(start -0.12065 0.2794)
			(end -0.12065 0.3048)
			(stroke
				(width 0.1)
				(type default)
			)
			(layer "F.Fab")
		)
		(fp_line
			(start 0.120396 0.2794)
			(end -0.12065 0.2794)
			(stroke
				(width 0.1)
				(type default)
			)
			(layer "F.Fab")
		)
		(fp_line
			(start -0.12065 -0.2794)
			(end 0.12065 -0.2794)
			(stroke
				(width 0.1)
				(type default)
			)
			(layer "F.Fab")
		)
		(fp_line
			(start 0.12065 -0.2794)
			(end 0.12065 -0.3048)
			(stroke
				(width 0.1)
				(type default)
			)
			(layer "F.Fab")
		)
		(fp_line
			(start 0.12065 -0.3048)
			(end 0.67945 -0.3048)
			(stroke
				(width 0.1)
				(type default)
			)
			(layer "F.Fab")
		)
		(fp_line
			(start 0.67945 -0.3048)
			(end 0.67945 0.3048)
			(stroke
				(width 0.1)
				(type default)
			)
			(layer "F.Fab")
		)
		(fp_line
			(start -0.67945 -0.305054)
			(end -0.12065 -0.305054)
			(stroke
				(width 0.1)
				(type default)
			)
			(layer "F.Fab")
		)
		(fp_line
			(start -0.12065 -0.305054)
			(end -0.12065 -0.2794)
			(stroke
				(width 0.1)
				(type default)
			)
			(layer "F.Fab")
		)
		(pad "1" smd circle
			(at -0.40005 0 270)
			(size 0 0)
			(layers "F.Cu" "F.Mask" "F.Paste")
			(net "SW_PVDDCR_CPU1_P0_BOOT1_R")
		)
		(pad "2" smd circle
			(at 0.40005 0 270)
			(size 0 0)
			(layers "F.Cu" "F.Mask" "F.Paste")
			(net "SW_PVDDCR_CPU1_P0_BOOTR1")
		)
	)
)
